(kicad_pcb
	(version 20260206)
	(generator "pcbnew")
	(generator_version "10.0")
	(general
		(thickness 1.6)
		(legacy_teardrops no)
	)
	(paper "A4")
	(title_block
		(title "Bryce Canyon_IOM_M2_16342-2_OCP.brd")
		(comment 1 "Bryce Canyon / footprints 42-48 of 1146")
	)
	(layers
		(0 "F.Cu" signal "TOP")
		(4 "In1.Cu" signal "L2GND")
		(6 "In2.Cu" signal "L3")
		(8 "In3.Cu" signal "L4VCC")
		(10 "In4.Cu" signal "L5VCC")
		(12 "In5.Cu" signal "L6")
		(14 "In6.Cu" signal "L7GND")
		(2 "B.Cu" signal "BOTTOM")
		(9 "F.Adhes" user "F.Adhesive")
		(11 "B.Adhes" user "B.Adhesive")
		(13 "F.Paste" user "Package Geometry/Pastemask Top")
		(15 "B.Paste" user "Package Geometry/Pastemask Bottom")
		(5 "F.SilkS" user "Ref Des/Silkscreen Top")
		(7 "B.SilkS" user "Ref Des/Silkscreen Bottom")
		(1 "F.Mask" user "Board Geometry/Soldermask Top")
		(3 "B.Mask" user "Board Geometry/Soldermask Bottom")
		(17 "Dwgs.User" user "User.Drawings")
		(19 "Cmts.User" user "User.Comments")
		(21 "Eco1.User" user "User.Eco1")
		(23 "Eco2.User" user "User.Eco2")
		(25 "Edge.Cuts" user "Board Geometry/Outline")
		(27 "Margin" user)
		(31 "F.CrtYd" user "Package Geometry/Place Bound Top")
		(29 "B.CrtYd" user "Package Geometry/Place Bound Bottom")
		(35 "F.Fab" user "Ref Des/Assembly Top")
		(33 "B.Fab" user "Ref Des/Assembly Bottom")
	)
	(footprint ""
		(layer "F.Cu")
		(at 46.970696 -124.827792 180)
		(property "Reference" "R296"
			(at 0 0 180)
			(layer "F.SilkS")
			(hide yes)
			(effects
				(font
					(size 1.27 1.27)
				)
			)
		)
		(property "Value" "2K2R2F-GP"
			(at 0.064008 -3.993896 180)
			(unlocked yes)
			(layer "F.Fab")
			(hide yes)
			(effects
				(font
					(size 1.016 1.016)
					(thickness 0.1524)
				)
			)
		)
		(property "Device Type" "R402H16"
			(at 0.064008 -5.517896 180)
			(unlocked yes)
			(layer "F.Fab")
			(hide yes)
			(effects
				(font
					(size 1.016 1.016)
					(thickness 0.1524)
				)
			)
		)
		(duplicate_pad_numbers_are_jumpers no)
		(fp_line
			(start 0.508 -0.9398)
			(end -0.508 -0.9398)
			(stroke
				(width 0.1524)
				(type default)
			)
			(layer "F.SilkS")
		)
		(fp_line
			(start -0.508 -0.9398)
			(end -0.508 0.9398)
			(stroke
				(width 0.1524)
				(type default)
			)
			(layer "F.SilkS")
		)
		(fp_rect
			(start -0.508 0.9398)
			(end 0.508 -0.9398)
			(stroke
				(width 0)
				(type default)
			)
			(fill no)
			(layer "F.CrtYd")
		)
		(fp_rect
			(start -0.508 0.9398)
			(end 0.508 -0.9398)
			(stroke
				(width 0)
				(type default)
			)
			(fill no)
			(layer "F.Fab")
		)
		(pad "1" smd custom
			(at 0 -0.4445 180)
			(size 0.1397 0.1397)
			(layers "F.Cu" "F.Mask" "F.Paste")
			(net "BMC_SMB2_CLK")
			(options
				(clearance outline)
				(anchor circle)
			)
			(primitives
				(gr_poly
					(pts
						(arc
							(start -0.1778 -0.2794)
							(mid -0.249642 -0.249642)
							(end -0.2794 -0.1778)
						)
						(arc
							(start -0.2794 0.1778)
							(mid -0.249642 0.249642)
							(end -0.1778 0.2794)
						)
						(arc
							(start 0.1778 0.2794)
							(mid 0.249642 0.249642)
							(end 0.2794 0.1778)
						)
						(arc
							(start 0.2794 -0.1778)
							(mid 0.249642 -0.249642)
							(end 0.1778 -0.2794)
						)
					)
					(width 0)
					(fill yes)
				)
			)
		)
		(pad "2" smd custom
			(at 0 0.4445 180)
			(size 0.1397 0.1397)
			(layers "F.Cu" "F.Mask" "F.Paste")
			(net "P3V3_STBY")
			(options
				(clearance outline)
				(anchor circle)
			)
			(primitives
				(gr_poly
					(pts
						(arc
							(start -0.1778 -0.2794)
							(mid -0.249642 -0.249642)
							(end -0.2794 -0.1778)
						)
						(arc
							(start -0.2794 0.1778)
							(mid -0.249642 0.249642)
							(end -0.1778 0.2794)
						)
						(arc
							(start 0.1778 0.2794)
							(mid 0.249642 0.249642)
							(end 0.2794 0.1778)
						)
						(arc
							(start 0.2794 -0.1778)
							(mid 0.249642 -0.249642)
							(end 0.1778 -0.2794)
						)
					)
					(width 0)
					(fill yes)
				)
			)
		)
	)
	(footprint ""
		(layer "F.Cu")
		(at 90.98407 -59.32551 90)
		(property "Reference" "D4"
			(at 0 0 90)
			(layer "F.SilkS")
			(hide yes)
			(effects
				(font
					(size 1.27 1.27)
				)
			)
		)
		(property "Value" "SMF15A-GP"
			(at -2.0955 1.2192 90)
			(unlocked yes)
			(layer "F.Fab")
			(hide yes)
			(effects
				(font
					(size 1.016 1.016)
					(thickness 0.1524)
				)
			)
		)
		(property "Device Type" "SOD123AK-2H43"
			(at -2.0955 -0.3048 90)
			(unlocked yes)
			(layer "F.Fab")
			(hide yes)
			(effects
				(font
					(size 1.016 1.016)
					(thickness 0.1524)
				)
			)
		)
		(duplicate_pad_numbers_are_jumpers no)
		(fp_line
			(start 1.1557 -2.7686)
			(end -1.1557 -2.7686)
			(stroke
				(width 0.1524)
				(type default)
			)
			(layer "F.SilkS")
		)
		(fp_line
			(start -1.1557 -2.7686)
			(end -1.1557 2.7686)
			(stroke
				(width 0.1524)
				(type default)
			)
			(layer "F.SilkS")
		)
		(fp_line
			(start 1.1557 2.7686)
			(end 1.1557 -2.7686)
			(stroke
				(width 0.1524)
				(type default)
			)
			(layer "F.SilkS")
		)
		(fp_line
			(start -1.1557 2.7686)
			(end 1.1557 2.7686)
			(stroke
				(width 0.1524)
				(type default)
			)
			(layer "F.SilkS")
		)
		(fp_line
			(start 1.1557 2.921)
			(end -1.1557 2.921)
			(stroke
				(width 0.508)
				(type default)
			)
			(layer "F.SilkS")
		)
		(fp_poly
			(pts
				(xy -0.4572 1.8669) (xy -0.4572 1.397) (xy -0.9017 1.397) (xy -0.9017 -1.397) (xy -0.4572 -1.397)
				(xy -0.4572 -1.8669) (xy 0.4572 -1.8669) (xy 0.4572 -1.397) (xy 0.9017 -1.397) (xy 0.9017 1.397)
				(xy 0.4572 1.397) (xy 0.4572 1.8669)
			)
			(stroke
				(width 0)
				(type default)
			)
			(fill no)
			(layer "F.CrtYd")
		)
		(fp_poly
			(pts
				(xy -1.4097 2.8448) (xy -1.4097 -2.8448) (xy 1.4097 -2.8448) (xy 1.4097 1.3716) (xy 0.9017 1.3716)
				(xy 0.9017 -1.397) (xy 0.4572 -1.397) (xy 0.4572 -1.8669) (xy -0.4572 -1.8669) (xy -0.4572 -1.397)
				(xy -0.9017 -1.397) (xy -0.9017 1.397) (xy -0.4572 1.397) (xy -0.4572 1.8669) (xy 0.4572 1.8669)
				(xy 0.4572 1.397) (xy 0.9017 1.397) (xy 0.9017 1.3843) (xy 1.4097 1.3843) (xy 1.4097 2.8448)
			)
			(stroke
				(width 0)
				(type default)
			)
			(fill no)
			(layer "F.CrtYd")
		)
		(fp_rect
			(start -1.4097 2.8448)
			(end 1.4097 -2.8448)
			(stroke
				(width 0)
				(type default)
			)
			(fill no)
			(layer "F.Fab")
		)
		(pad "A" smd rect
			(at 0 -1.75768 90)
			(size 1.143 1.4986)
			(layers "F.Cu" "F.Mask" "F.Paste")
			(net "P3V3_EN_R")
		)
		(pad "K" smd rect
			(at 0 1.75768 90)
			(size 1.143 1.4986)
			(layers "F.Cu" "F.Mask" "F.Paste")
			(net "P3V3_EN")
		)
	)
	(footprint ""
		(layer "F.Cu")
		(at 71.92518 -161.8615 90)
		(property "Reference" "C240"
			(at 0 0 90)
			(layer "F.SilkS")
			(hide yes)
			(effects
				(font
					(size 1.27 1.27)
				)
			)
		)
		(property "Value" "SC470P50V2KX-3GP"
			(at 1.1811 -2.7051 90)
			(unlocked yes)
			(layer "F.Fab")
			(hide yes)
			(effects
				(font
					(size 1.016 1.016)
					(thickness 0.1524)
				)
			)
		)
		(property "Device Type" "C402H22"
			(at 1.1811 -4.2291 90)
			(unlocked yes)
			(layer "F.Fab")
			(hide yes)
			(effects
				(font
					(size 1.016 1.016)
					(thickness 0.1524)
				)
			)
		)
		(duplicate_pad_numbers_are_jumpers no)
		(fp_rect
			(start -0.4318 0.9525)
			(end 0.4318 -0.9525)
			(stroke
				(width 0)
				(type default)
			)
			(fill no)
			(layer "F.CrtYd")
		)
		(fp_rect
			(start -0.4318 0.9525)
			(end 0.4318 -0.9525)
			(stroke
				(width 0)
				(type default)
			)
			(fill no)
			(layer "F.Fab")
		)
		(pad "1" smd custom
			(at 0 -0.4445 90)
			(size 0.1524 0.1524)
			(layers "F.Cu" "F.Mask" "F.Paste")
			(net "GND")
			(options
				(clearance outline)
				(anchor circle)
			)
			(primitives
				(gr_poly
					(pts
						(arc
							(start 0.3048 -0.2032)
							(mid 0.275042 -0.275042)
							(end 0.2032 -0.3048)
						)
						(arc
							(start -0.2032 -0.3048)
							(mid -0.275042 -0.275042)
							(end -0.3048 -0.2032)
						)
						(arc
							(start -0.3048 0.2032)
							(mid -0.275042 0.275042)
							(end -0.2032 0.3048)
						)
						(arc
							(start 0.2032 0.3048)
							(mid 0.275042 0.275042)
							(end 0.3048 0.2032)
						)
					)
					(width 0)
					(fill yes)
				)
			)
		)
		(pad "2" smd custom
			(at 0 0.4445 90)
			(size 0.1524 0.1524)
			(layers "F.Cu" "F.Mask" "F.Paste")
			(net "TPS74801_P1V15_STBY_SS")
			(options
				(clearance outline)
				(anchor circle)
			)
			(primitives
				(gr_poly
					(pts
						(arc
							(start 0.3048 -0.2032)
							(mid 0.275042 -0.275042)
							(end 0.2032 -0.3048)
						)
						(arc
							(start -0.2032 -0.3048)
							(mid -0.275042 -0.275042)
							(end -0.3048 -0.2032)
						)
						(arc
							(start -0.3048 0.2032)
							(mid -0.275042 0.275042)
							(end -0.2032 0.3048)
						)
						(arc
							(start 0.2032 0.3048)
							(mid 0.275042 0.275042)
							(end 0.3048 0.2032)
						)
					)
					(width 0)
					(fill yes)
				)
			)
		)
	)
	(footprint ""
		(layer "F.Cu")
		(at 206.756 -139.573 -135)
		(property "Reference" "VIA51"
			(at 0 0 225)
			(layer "F.SilkS")
			(hide yes)
			(effects
				(font
					(size 1.27 1.27)
				)
			)
		)
		(property "Value" "85OHM-8L-1D6MM-L16L18-GP"
			(at 4.064105 0.609655 225)
			(unlocked yes)
			(layer "F.Fab")
			(hide yes)
			(effects
				(font
					(size 1.016 1.016)
					(thickness 0.1524)
				)
			)
		)
		(property "Device Type" "VIA-PCIE-4P-368076"
			(at 4.064105 -0.914474 225)
			(unlocked yes)
			(layer "F.Fab")
			(hide yes)
			(effects
				(font
					(size 1.016 1.016)
					(thickness 0.1524)
				)
			)
		)
		(duplicate_pad_numbers_are_jumpers no)
		(fp_poly
			(pts
				(xy -1.841491 -0.381057) (xy 1.841509 -0.381058) (xy 1.841508 0.380942) (xy -1.841491 0.380942)
			)
			(stroke
				(width 0)
				(type default)
			)
			(fill no)
			(layer "F.CrtYd")
		)
		(fp_poly
			(pts
				(xy -1.841491 -0.381057) (xy 1.841509 -0.381058) (xy 1.841508 0.380942) (xy -1.841491 0.380942)
			)
			(stroke
				(width 0)
				(type default)
			)
			(fill no)
			(layer "F.Fab")
		)
		(pad "1" thru_hole circle
			(at -1.460499 0 225)
			(size 0.508 0.508)
			(drill 0.254)
			(layers "*.Cu" "*.Mask")
			(remove_unused_layers no)
			(net "GND")
			(clearance 0.127)
			(thermal_gap 0.127)
		)
		(pad "2" thru_hole circle
			(at -0.4445 0 225)
			(size 0.508 0.508)
			(drill 0.254)
			(layers "*.Cu" "*.Mask")
			(remove_unused_layers no)
			(net "PCIE_IOM_TO_COMP_8_DP")
			(clearance 0.127)
			(thermal_gap 0.127)
		)
		(pad "3" thru_hole circle
			(at 0.4445 0 225)
			(size 0.508 0.508)
			(drill 0.254)
			(layers "*.Cu" "*.Mask")
			(remove_unused_layers no)
			(net "PCIE_IOM_TO_COMP_8_DN")
			(clearance 0.127)
			(thermal_gap 0.127)
		)
		(pad "4" thru_hole circle
			(at 1.460499 0 225)
			(size 0.508 0.508)
			(drill 0.254)
			(layers "*.Cu" "*.Mask")
			(remove_unused_layers no)
			(net "GND")
			(clearance 0.127)
			(thermal_gap 0.127)
		)
	)
	(footprint ""
		(layer "F.Cu")
		(at 183.8452 -7.9756 180)
		(property "Reference" "R411"
			(at 0 0 180)
			(layer "F.SilkS")
			(hide yes)
			(effects
				(font
					(size 1.27 1.27)
				)
			)
		)
		(property "Value" "0R2J-2-GP"
			(at 0.064008 -3.993896 180)
			(unlocked yes)
			(layer "F.Fab")
			(hide yes)
			(effects
				(font
					(size 1.016 1.016)
					(thickness 0.1524)
				)
			)
		)
		(property "Device Type" "R402H16"
			(at 0.064008 -5.517896 180)
			(unlocked yes)
			(layer "F.Fab")
			(hide yes)
			(effects
				(font
					(size 1.016 1.016)
					(thickness 0.1524)
				)
			)
		)
		(duplicate_pad_numbers_are_jumpers no)
		(fp_line
			(start 0.508 -0.9398)
			(end -0.508 -0.9398)
			(stroke
				(width 0.1524)
				(type default)
			)
			(layer "F.SilkS")
		)
		(fp_line
			(start -0.508 -0.9398)
			(end -0.508 0.9398)
			(stroke
				(width 0.1524)
				(type default)
			)
			(layer "F.SilkS")
		)
		(fp_rect
			(start -0.508 0.9398)
			(end 0.508 -0.9398)
			(stroke
				(width 0)
				(type default)
			)
			(fill no)
			(layer "F.CrtYd")
		)
		(fp_rect
			(start -0.508 0.9398)
			(end 0.508 -0.9398)
			(stroke
				(width 0)
				(type default)
			)
			(fill no)
			(layer "F.Fab")
		)
		(pad "1" smd custom
			(at 0 -0.4445 180)
			(size 0.1397 0.1397)
			(layers "F.Cu" "F.Mask" "F.Paste")
			(net "BMC_ML_PWR_YELLOW_LED_R")
			(options
				(clearance outline)
				(anchor circle)
			)
			(primitives
				(gr_poly
					(pts
						(arc
							(start -0.1778 -0.2794)
							(mid -0.249642 -0.249642)
							(end -0.2794 -0.1778)
						)
						(arc
							(start -0.2794 0.1778)
							(mid -0.249642 0.249642)
							(end -0.1778 0.2794)
						)
						(arc
							(start 0.1778 0.2794)
							(mid 0.249642 0.249642)
							(end 0.2794 0.1778)
						)
						(arc
							(start 0.2794 -0.1778)
							(mid 0.249642 -0.249642)
							(end 0.1778 -0.2794)
						)
					)
					(width 0)
					(fill yes)
				)
			)
		)
		(pad "2" smd custom
			(at 0 0.4445 180)
			(size 0.1397 0.1397)
			(layers "F.Cu" "F.Mask" "F.Paste")
			(net "BMC_ML_PWR_YELLOW_LED")
			(options
				(clearance outline)
				(anchor circle)
			)
			(primitives
				(gr_poly
					(pts
						(arc
							(start -0.1778 -0.2794)
							(mid -0.249642 -0.249642)
							(end -0.2794 -0.1778)
						)
						(arc
							(start -0.2794 0.1778)
							(mid -0.249642 0.249642)
							(end -0.1778 0.2794)
						)
						(arc
							(start 0.1778 0.2794)
							(mid 0.249642 0.249642)
							(end 0.2794 0.1778)
						)
						(arc
							(start 0.2794 -0.1778)
							(mid 0.249642 -0.249642)
							(end 0.1778 -0.2794)
						)
					)
					(width 0)
					(fill yes)
				)
			)
		)
	)
	(footprint ""
		(layer "F.Cu")
		(at 112.638078 -13.13561 180)
		(property "Reference" "R457"
			(at 0 0 180)
			(layer "F.SilkS")
			(hide yes)
			(effects
				(font
					(size 1.27 1.27)
				)
			)
		)
		(property "Value" "100KR2J-4-GP"
			(at 0.064008 -3.993896 180)
			(unlocked yes)
			(layer "F.Fab")
			(hide yes)
			(effects
				(font
					(size 1.016 1.016)
					(thickness 0.1524)
				)
			)
		)
		(property "Device Type" "R402H15"
			(at 0.064008 -5.517896 180)
			(unlocked yes)
			(layer "F.Fab")
			(hide yes)
			(effects
				(font
					(size 1.016 1.016)
					(thickness 0.1524)
				)
			)
		)
		(duplicate_pad_numbers_are_jumpers no)
		(fp_line
			(start 0.508 -0.9398)
			(end -0.508 -0.9398)
			(stroke
				(width 0.1524)
				(type default)
			)
			(layer "F.SilkS")
		)
		(fp_line
			(start -0.508 -0.9398)
			(end -0.508 0.9398)
			(stroke
				(width 0.1524)
				(type default)
			)
			(layer "F.SilkS")
		)
		(fp_rect
			(start -0.508 0.9398)
			(end 0.508 -0.9398)
			(stroke
				(width 0)
				(type default)
			)
			(fill no)
			(layer "F.CrtYd")
		)
		(fp_rect
			(start -0.508 0.9398)
			(end 0.508 -0.9398)
			(stroke
				(width 0)
				(type default)
			)
			(fill no)
			(layer "F.Fab")
		)
		(pad "1" smd custom
			(at 0 -0.4445 180)
			(size 0.1397 0.1397)
			(layers "F.Cu" "F.Mask" "F.Paste")
			(net "MB0_VCAP_R")
			(options
				(clearance outline)
				(anchor circle)
			)
			(primitives
				(gr_poly
					(pts
						(arc
							(start -0.1778 -0.2794)
							(mid -0.249642 -0.249642)
							(end -0.2794 -0.1778)
						)
						(arc
							(start -0.2794 0.1778)
							(mid -0.249642 0.249642)
							(end -0.1778 0.2794)
						)
						(arc
							(start 0.1778 0.2794)
							(mid 0.249642 0.249642)
							(end 0.2794 0.1778)
						)
						(arc
							(start 0.2794 -0.1778)
							(mid 0.249642 -0.249642)
							(end 0.1778 -0.2794)
						)
					)
					(width 0)
					(fill yes)
				)
			)
		)
		(pad "2" smd custom
			(at 0 0.4445 180)
			(size 0.1397 0.1397)
			(layers "F.Cu" "F.Mask" "F.Paste")
			(net "MB0_PSET_R")
			(options
				(clearance outline)
				(anchor circle)
			)
			(primitives
				(gr_poly
					(pts
						(arc
							(start -0.1778 -0.2794)
							(mid -0.249642 -0.249642)
							(end -0.2794 -0.1778)
						)
						(arc
							(start -0.2794 0.1778)
							(mid -0.249642 0.249642)
							(end -0.1778 0.2794)
						)
						(arc
							(start 0.1778 0.2794)
							(mid 0.249642 0.249642)
							(end 0.2794 0.1778)
						)
						(arc
							(start 0.2794 -0.1778)
							(mid 0.249642 -0.249642)
							(end 0.1778 -0.2794)
						)
					)
					(width 0)
					(fill yes)
				)
			)
		)
	)
	(footprint ""
		(layer "F.Cu")
		(at 58.252868 -131.23037)
		(property "Reference" "R278"
			(at 0 0 0)
			(layer "F.SilkS")
			(hide yes)
			(effects
				(font
					(size 1.27 1.27)
				)
			)
		)
		(property "Value" "0R2J-2-GP"
			(at 0.064008 -3.993896 0)
			(unlocked yes)
			(layer "F.Fab")
			(hide yes)
			(effects
				(font
					(size 1.016 1.016)
					(thickness 0.1524)
				)
			)
		)
		(property "Device Type" "R402H16"
			(at 0.064008 -5.517896 0)
			(unlocked yes)
			(layer "F.Fab")
			(hide yes)
			(effects
				(font
					(size 1.016 1.016)
					(thickness 0.1524)
				)
			)
		)
		(duplicate_pad_numbers_are_jumpers no)
		(fp_line
			(start -0.508 -0.9398)
			(end -0.508 0.9398)
			(stroke
				(width 0.1524)
				(type default)
			)
			(layer "F.SilkS")
		)
		(fp_line
			(start 0.508 -0.9398)
			(end -0.508 -0.9398)
			(stroke
				(width 0.1524)
				(type default)
			)
			(layer "F.SilkS")
		)
		(fp_rect
			(start -0.508 0.9398)
			(end 0.508 -0.9398)
			(stroke
				(width 0)
				(type default)
			)
			(fill no)
			(layer "F.CrtYd")
		)
		(fp_rect
			(start -0.508 0.9398)
			(end 0.508 -0.9398)
			(stroke
				(width 0)
				(type default)
			)
			(fill no)
			(layer "F.Fab")
		)
		(pad "1" smd custom
			(at 0 -0.4445)
			(size 0.1397 0.1397)
			(layers "F.Cu" "F.Mask" "F.Paste")
			(net "RSTBTN_OUT_N_R")
			(options
				(clearance outline)
				(anchor circle)
			)
			(primitives
				(gr_poly
					(pts
						(arc
							(start -0.1778 -0.2794)
							(mid -0.249642 -0.249642)
							(end -0.2794 -0.1778)
						)
						(arc
							(start -0.2794 0.1778)
							(mid -0.249642 0.249642)
							(end -0.1778 0.2794)
						)
						(arc
							(start 0.1778 0.2794)
							(mid 0.249642 0.249642)
							(end 0.2794 0.1778)
						)
						(arc
							(start 0.2794 -0.1778)
							(mid 0.249642 -0.249642)
							(end 0.1778 -0.2794)
						)
					)
					(width 0)
					(fill yes)
				)
			)
		)
		(pad "2" smd custom
			(at 0 0.4445)
			(size 0.1397 0.1397)
			(layers "F.Cu" "F.Mask" "F.Paste")
			(net "RSTBTN_OUT_N")
			(options
				(clearance outline)
				(anchor circle)
			)
			(primitives
				(gr_poly
					(pts
						(arc
							(start -0.1778 -0.2794)
							(mid -0.249642 -0.249642)
							(end -0.2794 -0.1778)
						)
						(arc
							(start -0.2794 0.1778)
							(mid -0.249642 0.249642)
							(end -0.1778 0.2794)
						)
						(arc
							(start 0.1778 0.2794)
							(mid 0.249642 0.249642)
							(end 0.2794 0.1778)
						)
						(arc
							(start 0.2794 -0.1778)
							(mid 0.249642 -0.249642)
							(end 0.1778 -0.2794)
						)
					)
					(width 0)
					(fill yes)
				)
			)
		)
	)
)
